FILE_TYPE=LIBRARY_PARTS;
primitive 'PI3EQX12902AZLEX';
  pin
    'VDD1':
      PIN_NUMBER='(1)';
      PINUSE='POWER';
      NO_LOAD_CHECK='Both';
      NO_IO_CHECK='Both';
      NO_ASSERT_CHECK='TRUE';
      NO_DIR_CHECK='TRUE';
      ALLOW_CONNECT='TRUE';
    'AIP':
      PIN_NUMBER='(2)';
      INPUT_LOAD='(-0.01,0.01)';
    'AIN':
      PIN_NUMBER='(3)';
      INPUT_LOAD='(-0.01,0.01)';
    'GND1':
      PIN_NUMBER='(4)';
      PINUSE='POWER';
      NO_LOAD_CHECK='Both';
      NO_IO_CHECK='Both';
      NO_ASSERT_CHECK='TRUE';
      NO_DIR_CHECK='TRUE';
      ALLOW_CONNECT='TRUE';
    'TEST#':
      PIN_NUMBER='(5)';
      INPUT_LOAD='(-0.01,0.01)';
    'GND2':
      PIN_NUMBER='(6)';
      PINUSE='POWER';
      NO_LOAD_CHECK='Both';
      NO_IO_CHECK='Both';
      NO_ASSERT_CHECK='TRUE';
      NO_DIR_CHECK='TRUE';
      ALLOW_CONNECT='TRUE';
    'GND3':
      PIN_NUMBER='(7)';
      PINUSE='POWER';
      NO_LOAD_CHECK='Both';
      NO_IO_CHECK='Both';
      NO_ASSERT_CHECK='TRUE';
      NO_DIR_CHECK='TRUE';
      ALLOW_CONNECT='TRUE';
    'BON':
      PIN_NUMBER='(8)';
      OUTPUT_LOAD='(1.0,-1.0)';
    'BOP':
      PIN_NUMBER='(9)';
      OUTPUT_LOAD='(1.0,-1.0)';
    'VDD2':
      PIN_NUMBER='(10)';
      PINUSE='POWER';
      NO_LOAD_CHECK='Both';
      NO_IO_CHECK='Both';
      NO_ASSERT_CHECK='TRUE';
      NO_DIR_CHECK='TRUE';
      ALLOW_CONNECT='TRUE';
    'EN#':
      PIN_NUMBER='(11)';
      INPUT_LOAD='(-0.01,0.01)';
    'SWB':
      PIN_NUMBER='(12)';
      INPUT_LOAD='(-0.01,0.01)';
    'GND4':
      PIN_NUMBER='(13)';
      PINUSE='POWER';
      NO_LOAD_CHECK='Both';
      NO_IO_CHECK='Both';
      NO_ASSERT_CHECK='TRUE';
      NO_DIR_CHECK='TRUE';
      ALLOW_CONNECT='TRUE';
    'FGB':
      PIN_NUMBER='(14)';
      INPUT_LOAD='(-0.01,0.01)';
    'EQB1':
      PIN_NUMBER='(15)';
      INPUT_LOAD='(-0.01,0.01)';
    'VDD3':
      PIN_NUMBER='(16)';
      PINUSE='POWER';
      NO_LOAD_CHECK='Both';
      NO_IO_CHECK='Both';
      NO_ASSERT_CHECK='TRUE';
      NO_DIR_CHECK='TRUE';
      ALLOW_CONNECT='TRUE';
    'BIP':
      PIN_NUMBER='(17)';
      INPUT_LOAD='(-0.01,0.01)';
    'BIN':
      PIN_NUMBER='(18)';
      INPUT_LOAD='(-0.01,0.01)';
    'GND5':
      PIN_NUMBER='(19)';
      PINUSE='POWER';
      NO_LOAD_CHECK='Both';
      NO_IO_CHECK='Both';
      NO_ASSERT_CHECK='TRUE';
      NO_DIR_CHECK='TRUE';
      ALLOW_CONNECT='TRUE';
    'EQB0':
      PIN_NUMBER='(20)';
      INPUT_LOAD='(-0.01,0.01)';
    'EQA0':
      PIN_NUMBER='(21)';
      INPUT_LOAD='(-0.01,0.01)';
    'GND6':
      PIN_NUMBER='(22)';
      PINUSE='POWER';
      NO_LOAD_CHECK='Both';
      NO_IO_CHECK='Both';
      NO_ASSERT_CHECK='TRUE';
      NO_DIR_CHECK='TRUE';
      ALLOW_CONNECT='TRUE';
    'AON':
      PIN_NUMBER='(23)';
      OUTPUT_LOAD='(1.0,-1.0)';
    'AOP':
      PIN_NUMBER='(24)';
      OUTPUT_LOAD='(1.0,-1.0)';
    'VDD4':
      PIN_NUMBER='(25)';
      PINUSE='POWER';
      NO_LOAD_CHECK='Both';
      NO_IO_CHECK='Both';
      NO_ASSERT_CHECK='TRUE';
      NO_DIR_CHECK='TRUE';
      ALLOW_CONNECT='TRUE';
    'EQA1':
      PIN_NUMBER='(26)';
      INPUT_LOAD='(-0.01,0.01)';
    'FGA':
      PIN_NUMBER='(27)';
      INPUT_LOAD='(-0.01,0.01)';
    'GND7':
      PIN_NUMBER='(28)';
      PINUSE='POWER';
      NO_LOAD_CHECK='Both';
      NO_IO_CHECK='Both';
      NO_ASSERT_CHECK='TRUE';
      NO_DIR_CHECK='TRUE';
      ALLOW_CONNECT='TRUE';
    'SWA':
      PIN_NUMBER='(29)';
      INPUT_LOAD='(-0.01,0.01)';
    'MODE':
      PIN_NUMBER='(30)';
      INPUT_LOAD='(-0.01,0.01)';
    'GND_TH':
      PIN_NUMBER='(TH)';
      PINUSE='POWER';
      NO_LOAD_CHECK='Both';
      NO_IO_CHECK='Both';
      NO_ASSERT_CHECK='TRUE';
      NO_DIR_CHECK='TRUE';
      ALLOW_CONNECT='TRUE';
  end_pin;
  body
    PART_NAME='PI3EQX12902AZLEX';
    BODY_NAME='PI3EQX12902AZLEX';
    PHYS_DES_PREFIX='U';
    CLASS='IC';
  end_body;
end_primitive;

END.
